# S9S_MB_2U (Grand Teton) — schematic netlist excerpt (pin names and nets, part order shuffled) for the footprints in the layout excerpt that follows; sources: Cadence DE-HDL packaged netlist, KiCad conversion of 03242023_DA0F0TMBIJ0_F0T_Motherboard_J_brd_V01_OCP.brd

ME14  ME_DUMMY_SYMBOL  PICKUP_SMDC20 EMPTY  pkg PICKUP_SMDC20  page 312
R704  Q_RES  10K 1% EMPTY  pkg 0402LF  page 130 : A = RST_PLD_CPU1_DRAM_EF_N ; B = GND
L13  Q_INDUCTOR  FCM2012KF-601T/0.5A IND  pkg SMLF  page 210 : \1\ = P3V3_AUX ; \2\ = P3V3_AUX_CLK_GEN_VDDXTAL_CK440
PC412_P1_1  Q_CAP  22UF 4V 20% X6S  pkg C0805  page 289 : A = PVCCFA_EHV_FIVRA_CPU1 ; B = GND

(kicad_pcb
	(version 20260206)
	(generator "pcbnew")
	(generator_version "10.0")
	(general
		(thickness 1.6)
		(legacy_teardrops no)
	)
	(paper "A4")
	(title_block
		(title "03242023_DA0F0TMBIJ0_F0T_Motherboard_J_brd_V01_OCP.brd")
		(comment 1 "Grand Teton / footprints 5277-5280 of 6105")
	)
	(layers
		(0 "F.Cu" signal "TOP")
		(4 "In1.Cu" signal "GND")
		(6 "In2.Cu" signal "IN1")
		(8 "In3.Cu" signal "GND1")
		(10 "In4.Cu" signal "IN2")
		(12 "In5.Cu" signal "GND2")
		(14 "In6.Cu" signal "IN3")
		(16 "In7.Cu" signal "GND3")
		(18 "In8.Cu" signal "VCC")
		(20 "In9.Cu" signal "VCC1")
		(22 "In10.Cu" signal "GND4")
		(24 "In11.Cu" signal "IN4")
		(26 "In12.Cu" signal "GND5")
		(28 "In13.Cu" signal "IN5")
		(30 "In14.Cu" signal "GND6")
		(32 "In15.Cu" signal "IN6")
		(34 "In16.Cu" signal "GND7")
		(2 "B.Cu" signal "BOTTOM")
		(9 "F.Adhes" user "F.Adhesive")
		(11 "B.Adhes" user "B.Adhesive")
		(13 "F.Paste" user "Package Geometry/Pastemask Top")
		(15 "B.Paste" user "Package Geometry/Pastemask Bottom")
		(5 "F.SilkS" user "Ref Des/Silkscreen Top")
		(7 "B.SilkS" user "Ref Des/Silkscreen Bottom")
		(1 "F.Mask" user "Board Geometry/Soldermask Top")
		(3 "B.Mask" user "Board Geometry/Soldermask Bottom")
		(17 "Dwgs.User" user "User.Drawings")
		(19 "Cmts.User" user "User.Comments")
		(21 "Eco1.User" user "User.Eco1")
		(23 "Eco2.User" user "User.Eco2")
		(25 "Edge.Cuts" user "Board Geometry/Outline")
		(27 "Margin" user)
		(31 "F.CrtYd" user "Package Geometry/Place Bound Top")
		(29 "B.CrtYd" user "Package Geometry/Place Bound Bottom")
		(35 "F.Fab" user "Ref Des/Assembly Top")
		(33 "B.Fab" user "Ref Des/Assembly Bottom")
	)
	(footprint ""
		(layer "B.Cu")
		(at 188.190886 -193.599816 -90)
		(property "Reference" "R704"
			(at 0 0 90)
			(layer "B.SilkS")
			(hide yes)
			(effects
				(font
					(size 1.27 1.27)
				)
				(justify mirror)
			)
		)
		(property "Value" ""
			(at 0 0 90)
			(layer "B.Fab")
			(effects
				(font
					(size 1.27 1.27)
				)
				(justify mirror)
			)
		)
		(duplicate_pad_numbers_are_jumpers no)
		(fp_line
			(start -0.7874 0.4064)
			(end 0.7874 0.4064)
			(stroke
				(width 0.1524)
				(type default)
			)
			(layer "B.SilkS")
		)
		(fp_line
			(start 0.7874 0.4064)
			(end 0.7874 -0.4064)
			(stroke
				(width 0.1524)
				(type default)
			)
			(layer "B.SilkS")
		)
		(fp_line
			(start -0.7874 -0.4064)
			(end -0.7874 0.4064)
			(stroke
				(width 0.1524)
				(type default)
			)
			(layer "B.SilkS")
		)
		(fp_line
			(start 0.7874 -0.4064)
			(end -0.7874 -0.4064)
			(stroke
				(width 0.1524)
				(type default)
			)
			(layer "B.SilkS")
		)
		(fp_line
			(start -0.67945 0.3048)
			(end -0.120396 0.3048)
			(stroke
				(width 0.1)
				(type default)
			)
			(layer "B.Fab")
		)
		(fp_line
			(start -0.120396 0.3048)
			(end -0.120396 0.2794)
			(stroke
				(width 0.1)
				(type default)
			)
			(layer "B.Fab")
		)
		(fp_line
			(start 0.12065 0.3048)
			(end 0.67945 0.3048)
			(stroke
				(width 0.1)
				(type default)
			)
			(layer "B.Fab")
		)
		(fp_line
			(start 0.67945 0.3048)
			(end 0.67945 -0.305054)
			(stroke
				(width 0.1)
				(type default)
			)
			(layer "B.Fab")
		)
		(fp_line
			(start -0.120396 0.2794)
			(end 0.12065 0.2794)
			(stroke
				(width 0.1)
				(type default)
			)
			(layer "B.Fab")
		)
		(fp_line
			(start 0.12065 0.2794)
			(end 0.12065 0.3048)
			(stroke
				(width 0.1)
				(type default)
			)
			(layer "B.Fab")
		)
		(fp_line
			(start -0.12065 -0.2794)
			(end -0.12065 -0.3048)
			(stroke
				(width 0.1)
				(type default)
			)
			(layer "B.Fab")
		)
		(fp_line
			(start 0.12065 -0.2794)
			(end -0.12065 -0.2794)
			(stroke
				(width 0.1)
				(type default)
			)
			(layer "B.Fab")
		)
		(fp_line
			(start -0.67945 -0.3048)
			(end -0.67945 0.3048)
			(stroke
				(width 0.1)
				(type default)
			)
			(layer "B.Fab")
		)
		(fp_line
			(start -0.12065 -0.3048)
			(end -0.67945 -0.3048)
			(stroke
				(width 0.1)
				(type default)
			)
			(layer "B.Fab")
		)
		(fp_line
			(start 0.12065 -0.305054)
			(end 0.12065 -0.2794)
			(stroke
				(width 0.1)
				(type default)
			)
			(layer "B.Fab")
		)
		(fp_line
			(start 0.67945 -0.305054)
			(end 0.12065 -0.305054)
			(stroke
				(width 0.1)
				(type default)
			)
			(layer "B.Fab")
		)
		(pad "1" smd circle
			(at 0.40005 0 90)
			(size 0 0)
			(layers "B.Cu" "B.Mask" "B.Paste")
			(net "RST_PLD_CPU1_DRAM_EF_N")
		)
		(pad "2" smd circle
			(at -0.40005 0 90)
			(size 0 0)
			(layers "B.Cu" "B.Mask" "B.Paste")
			(net "GND")
		)
	)
	(footprint ""
		(layer "B.Cu")
		(at 376.83694 -130.90906)
		(property "Reference" "ME14"
			(at 9.652 -9.540748 0)
			(unlocked yes)
			(layer "B.SilkS")
			(effects
				(font
					(size 0.7874 0.5842)
					(thickness 0.1524)
				)
				(justify left mirror)
			)
		)
		(property "Value" ""
			(at 0 0 0)
			(layer "B.Fab")
			(effects
				(font
					(size 1.27 1.27)
				)
				(justify mirror)
			)
		)
		(duplicate_pad_numbers_are_jumpers no)
		(zone
			(layer "B.Cu")
			(hatch none 0.5)
			(connect_pads
				(clearance 0)
			)
			(min_thickness 0.25)
			(keepout
				(tracks allowed)
				(vias allowed)
				(pads allowed)
				(copperpour allowed)
				(footprints not_allowed)
			)
			(placement
				(enabled no)
				(sheetname "")
			)
			(fill
				(thermal_gap 0.5)
				(thermal_bridge_width 0.5)
				(island_removal_mode 0)
			)
			(polygon
				(pts
					(arc
						(start 386.83692 -130.90906)
						(mid 366.83696 -130.90906)
						(end 386.83692 -130.90906)
					)
				)
			)
		)
	)
	(footprint ""
		(layer "B.Cu")
		(at 175.469804 -344.941906 -90)
		(property "Reference" "PC412_P1_1"
			(at 0 0 90)
			(layer "B.SilkS")
			(hide yes)
			(effects
				(font
					(size 1.27 1.27)
				)
				(justify mirror)
			)
		)
		(property "Value" ""
			(at 0 0 90)
			(layer "B.Fab")
			(effects
				(font
					(size 1.27 1.27)
				)
				(justify mirror)
			)
		)
		(duplicate_pad_numbers_are_jumpers no)
		(fp_line
			(start -1.524 0.762)
			(end 1.524 0.762)
			(stroke
				(width 0.1524)
				(type default)
			)
			(layer "B.SilkS")
		)
		(fp_line
			(start 1.524 0.762)
			(end 1.524 -0.762)
			(stroke
				(width 0.1524)
				(type default)
			)
			(layer "B.SilkS")
		)
		(fp_line
			(start -1.524 -0.762)
			(end -1.524 0.762)
			(stroke
				(width 0.1524)
				(type default)
			)
			(layer "B.SilkS")
		)
		(fp_line
			(start 1.524 -0.762)
			(end -1.524 -0.762)
			(stroke
				(width 0.1524)
				(type default)
			)
			(layer "B.SilkS")
		)
		(fp_line
			(start -1.1049 0.724916)
			(end -1.1049 -0.724916)
			(stroke
				(width 0.1)
				(type default)
			)
			(layer "B.Fab")
		)
		(fp_line
			(start 1.1049 0.724916)
			(end -1.1049 0.724916)
			(stroke
				(width 0.1)
				(type default)
			)
			(layer "B.Fab")
		)
		(fp_line
			(start -1.1049 -0.724916)
			(end 1.1049 -0.724916)
			(stroke
				(width 0.1)
				(type default)
			)
			(layer "B.Fab")
		)
		(fp_line
			(start 1.1049 -0.724916)
			(end 1.1049 0.724916)
			(stroke
				(width 0.1)
				(type default)
			)
			(layer "B.Fab")
		)
		(pad "1" smd rect
			(at 0.889 0 270)
			(size 1.016 1.27)
			(layers "B.Cu" "B.Mask" "B.Paste")
			(net "PVCCFA_EHV_FIVRA_CPU1")
		)
		(pad "2" smd rect
			(at -0.889 0 270)
			(size 1.016 1.27)
			(layers "B.Cu" "B.Mask" "B.Paste")
			(net "GND")
		)
	)
	(footprint ""
		(layer "B.Cu")
		(at 239.091724 -97.084642 180)
		(property "Reference" "L13"
			(at 0 0 0)
			(layer "B.SilkS")
			(hide yes)
			(effects
				(font
					(size 1.27 1.27)
				)
				(justify mirror)
			)
		)
		(property "Value" ""
			(at 0 0 0)
			(layer "B.Fab")
			(effects
				(font
					(size 1.27 1.27)
				)
				(justify mirror)
			)
		)
		(duplicate_pad_numbers_are_jumpers no)
		(fp_line
			(start 1.63576 -0.8128)
			(end 1.63576 0.8128)
			(stroke
				(width 0.1524)
				(type default)
			)
			(layer "B.SilkS")
		)
		(fp_line
			(start 1.63576 -0.8128)
			(end -1.63576 -0.8128)
			(stroke
				(width 0.1524)
				(type default)
			)
			(layer "B.SilkS")
		)
		(fp_line
			(start -1.63576 0.8128)
			(end 1.63576 0.8128)
			(stroke
				(width 0.1524)
				(type default)
			)
			(layer "B.SilkS")
		)
		(fp_line
			(start -1.63576 -0.8128)
			(end -1.63576 0.8128)
			(stroke
				(width 0.1524)
				(type default)
			)
			(layer "B.SilkS")
		)
		(fp_line
			(start 1.56083 0.7366)
			(end 1.524 0.7366)
			(stroke
				(width 0.1)
				(type default)
			)
			(layer "B.Fab")
		)
		(fp_line
			(start 1.56083 -0.738632)
			(end 1.56083 0.7366)
			(stroke
				(width 0.1)
				(type default)
			)
			(layer "B.Fab")
		)
		(fp_line
			(start 1.524 0.7366)
			(end -1.524 0.7366)
			(stroke
				(width 0.1)
				(type default)
			)
			(layer "B.Fab")
		)
		(fp_line
			(start -1.524 0.7366)
			(end -1.560576 0.7366)
			(stroke
				(width 0.1)
				(type default)
			)
			(layer "B.Fab")
		)
		(fp_line
			(start -1.560576 0.7366)
			(end -1.560576 -0.738632)
			(stroke
				(width 0.1)
				(type default)
			)
			(layer "B.Fab")
		)
		(fp_line
			(start -1.560576 -0.738632)
			(end 1.56083 -0.738632)
			(stroke
				(width 0.1)
				(type default)
			)
			(layer "B.Fab")
		)
		(pad "1" smd rect
			(at 0.94996 0 180)
			(size 1.1176 1.3716)
			(layers "B.Cu" "B.Mask" "B.Paste")
			(net "P3V3_AUX")
		)
		(pad "2" smd rect
			(at -0.94996 0 180)
			(size 1.1176 1.3716)
			(layers "B.Cu" "B.Mask" "B.Paste")
			(net "P3V3_AUX_CLK_GEN_VDDXTAL_CK440")
		)
	)
)
